# T6G (Grand Teton) — schematic netlist excerpt (pin names and nets, part order shuffled) for the footprints in the layout excerpt that follows; sources: Cadence DE-HDL packaged netlist, KiCad conversion of 04192023_DAF0TMB3IC0_F0TG_MB_C_brd_V02_OCP.brd

PC5328  Q_CAP  1UF 25V 10% X6S  pkg C0402  page 134 : A = P3V3_AUX ; B = GND
R2586  Q_RES  0 5% CHIP  pkg 0402LF  page 262 : A = HSC_EN ; B = HSC_EN_R
H3  HOLE  EMPTY  pkg TH  page 230 : \1\ = GND

(kicad_pcb
	(version 20260206)
	(generator "pcbnew")
	(generator_version "10.0")
	(general
		(thickness 1.6)
		(legacy_teardrops no)
	)
	(paper "A4")
	(title_block
		(title "04192023_DAF0TMB3IC0_F0TG_MB_C_brd_V02_OCP.brd")
		(comment 1 "Grand Teton / footprints 1584-1586 of 8354")
	)
	(layers
		(0 "F.Cu" signal "TOP")
		(4 "In1.Cu" signal "GND")
		(6 "In2.Cu" signal "IN1")
		(8 "In3.Cu" signal "GND1")
		(10 "In4.Cu" signal "IN2")
		(12 "In5.Cu" signal "GND2")
		(14 "In6.Cu" signal "IN3")
		(16 "In7.Cu" signal "GND3")
		(18 "In8.Cu" signal "VCC")
		(20 "In9.Cu" signal "VCC1")
		(22 "In10.Cu" signal "GND4")
		(24 "In11.Cu" signal "IN4")
		(26 "In12.Cu" signal "GND5")
		(28 "In13.Cu" signal "IN5")
		(30 "In14.Cu" signal "GND6")
		(32 "In15.Cu" signal "IN6")
		(34 "In16.Cu" signal "GND7")
		(2 "B.Cu" signal "BOTTOM")
		(9 "F.Adhes" user "F.Adhesive")
		(11 "B.Adhes" user "B.Adhesive")
		(13 "F.Paste" user "Package Geometry/Pastemask Top")
		(15 "B.Paste" user "Package Geometry/Pastemask Bottom")
		(5 "F.SilkS" user "Ref Des/Silkscreen Top")
		(7 "B.SilkS" user "Ref Des/Silkscreen Bottom")
		(1 "F.Mask" user "Board Geometry/Soldermask Top")
		(3 "B.Mask" user "Board Geometry/Soldermask Bottom")
		(17 "Dwgs.User" user "User.Drawings")
		(19 "Cmts.User" user "User.Comments")
		(21 "Eco1.User" user "User.Eco1")
		(23 "Eco2.User" user "User.Eco2")
		(25 "Edge.Cuts" user "Board Geometry/Outline")
		(27 "Margin" user)
		(31 "F.CrtYd" user "Package Geometry/Place Bound Top")
		(29 "B.CrtYd" user "Package Geometry/Place Bound Bottom")
		(35 "F.Fab" user "Ref Des/Assembly Top")
		(33 "B.Fab" user "Ref Des/Assembly Bottom")
	)
	(footprint ""
		(layer "F.Cu")
		(at 184.3405 -397.848582 180)
		(property "Reference" "R2586"
			(at 0 0 180)
			(layer "F.SilkS")
			(hide yes)
			(effects
				(font
					(size 1.27 1.27)
				)
			)
		)
		(property "Value" ""
			(at 0 0 180)
			(layer "F.Fab")
			(effects
				(font
					(size 1.27 1.27)
				)
			)
		)
		(duplicate_pad_numbers_are_jumpers no)
		(fp_line
			(start 0.7874 0.4064)
			(end -0.7874 0.4064)
			(stroke
				(width 0.1524)
				(type default)
			)
			(layer "F.SilkS")
		)
		(fp_line
			(start 0.7874 -0.4064)
			(end 0.7874 0.4064)
			(stroke
				(width 0.1524)
				(type default)
			)
			(layer "F.SilkS")
		)
		(fp_line
			(start -0.7874 0.4064)
			(end -0.7874 -0.4064)
			(stroke
				(width 0.1524)
				(type default)
			)
			(layer "F.SilkS")
		)
		(fp_line
			(start -0.7874 -0.4064)
			(end 0.7874 -0.4064)
			(stroke
				(width 0.1524)
				(type default)
			)
			(layer "F.SilkS")
		)
		(fp_line
			(start 0.67945 0.3048)
			(end 0.120396 0.3048)
			(stroke
				(width 0.1)
				(type default)
			)
			(layer "F.Fab")
		)
		(fp_line
			(start 0.67945 -0.3048)
			(end 0.67945 0.3048)
			(stroke
				(width 0.1)
				(type default)
			)
			(layer "F.Fab")
		)
		(fp_line
			(start 0.12065 -0.2794)
			(end 0.12065 -0.3048)
			(stroke
				(width 0.1)
				(type default)
			)
			(layer "F.Fab")
		)
		(fp_line
			(start 0.12065 -0.3048)
			(end 0.67945 -0.3048)
			(stroke
				(width 0.1)
				(type default)
			)
			(layer "F.Fab")
		)
		(fp_line
			(start 0.120396 0.3048)
			(end 0.120396 0.2794)
			(stroke
				(width 0.1)
				(type default)
			)
			(layer "F.Fab")
		)
		(fp_line
			(start 0.120396 0.2794)
			(end -0.12065 0.2794)
			(stroke
				(width 0.1)
				(type default)
			)
			(layer "F.Fab")
		)
		(fp_line
			(start -0.12065 0.3048)
			(end -0.67945 0.3048)
			(stroke
				(width 0.1)
				(type default)
			)
			(layer "F.Fab")
		)
		(fp_line
			(start -0.12065 0.2794)
			(end -0.12065 0.3048)
			(stroke
				(width 0.1)
				(type default)
			)
			(layer "F.Fab")
		)
		(fp_line
			(start -0.12065 -0.2794)
			(end 0.12065 -0.2794)
			(stroke
				(width 0.1)
				(type default)
			)
			(layer "F.Fab")
		)
		(fp_line
			(start -0.12065 -0.305054)
			(end -0.12065 -0.2794)
			(stroke
				(width 0.1)
				(type default)
			)
			(layer "F.Fab")
		)
		(fp_line
			(start -0.67945 0.3048)
			(end -0.67945 -0.305054)
			(stroke
				(width 0.1)
				(type default)
			)
			(layer "F.Fab")
		)
		(fp_line
			(start -0.67945 -0.305054)
			(end -0.12065 -0.305054)
			(stroke
				(width 0.1)
				(type default)
			)
			(layer "F.Fab")
		)
		(pad "1" smd circle
			(at -0.40005 0 180)
			(size 0 0)
			(layers "F.Cu" "F.Mask" "F.Paste")
			(net "HSC_EN")
		)
		(pad "2" smd circle
			(at 0.40005 0 180)
			(size 0 0)
			(layers "F.Cu" "F.Mask" "F.Paste")
			(net "HSC_EN_R")
		)
	)
	(footprint ""
		(layer "F.Cu")
		(at 435.997858 -107.78236 180)
		(property "Reference" "PC5328"
			(at 0 0 180)
			(layer "F.SilkS")
			(hide yes)
			(effects
				(font
					(size 1.27 1.27)
				)
			)
		)
		(property "Value" ""
			(at 0 0 180)
			(layer "F.Fab")
			(effects
				(font
					(size 1.27 1.27)
				)
			)
		)
		(duplicate_pad_numbers_are_jumpers no)
		(fp_line
			(start 0.7874 0.4064)
			(end -0.7874 0.4064)
			(stroke
				(width 0.1524)
				(type default)
			)
			(layer "F.SilkS")
		)
		(fp_line
			(start 0.7874 -0.4064)
			(end 0.7874 0.4064)
			(stroke
				(width 0.1524)
				(type default)
			)
			(layer "F.SilkS")
		)
		(fp_line
			(start -0.7874 0.4064)
			(end -0.7874 -0.4064)
			(stroke
				(width 0.1524)
				(type default)
			)
			(layer "F.SilkS")
		)
		(fp_line
			(start -0.7874 -0.4064)
			(end 0.7874 -0.4064)
			(stroke
				(width 0.1524)
				(type default)
			)
			(layer "F.SilkS")
		)
		(fp_line
			(start 0.67945 0.3048)
			(end 0.120396 0.3048)
			(stroke
				(width 0.1)
				(type default)
			)
			(layer "F.Fab")
		)
		(fp_line
			(start 0.67945 -0.3048)
			(end 0.67945 0.3048)
			(stroke
				(width 0.1)
				(type default)
			)
			(layer "F.Fab")
		)
		(fp_line
			(start 0.12065 -0.2794)
			(end 0.12065 -0.3048)
			(stroke
				(width 0.1)
				(type default)
			)
			(layer "F.Fab")
		)
		(fp_line
			(start 0.12065 -0.3048)
			(end 0.67945 -0.3048)
			(stroke
				(width 0.1)
				(type default)
			)
			(layer "F.Fab")
		)
		(fp_line
			(start 0.120396 0.3048)
			(end 0.120396 0.2794)
			(stroke
				(width 0.1)
				(type default)
			)
			(layer "F.Fab")
		)
		(fp_line
			(start 0.120396 0.2794)
			(end -0.12065 0.2794)
			(stroke
				(width 0.1)
				(type default)
			)
			(layer "F.Fab")
		)
		(fp_line
			(start -0.12065 0.3048)
			(end -0.67945 0.3048)
			(stroke
				(width 0.1)
				(type default)
			)
			(layer "F.Fab")
		)
		(fp_line
			(start -0.12065 0.2794)
			(end -0.12065 0.3048)
			(stroke
				(width 0.1)
				(type default)
			)
			(layer "F.Fab")
		)
		(fp_line
			(start -0.12065 -0.2794)
			(end 0.12065 -0.2794)
			(stroke
				(width 0.1)
				(type default)
			)
			(layer "F.Fab")
		)
		(fp_line
			(start -0.12065 -0.305054)
			(end -0.12065 -0.2794)
			(stroke
				(width 0.1)
				(type default)
			)
			(layer "F.Fab")
		)
		(fp_line
			(start -0.67945 0.3048)
			(end -0.67945 -0.305054)
			(stroke
				(width 0.1)
				(type default)
			)
			(layer "F.Fab")
		)
		(fp_line
			(start -0.67945 -0.305054)
			(end -0.12065 -0.305054)
			(stroke
				(width 0.1)
				(type default)
			)
			(layer "F.Fab")
		)
		(pad "1" smd circle
			(at -0.40005 0 180)
			(size 0 0)
			(layers "F.Cu" "F.Mask" "F.Paste")
			(net "P3V3_AUX")
		)
		(pad "2" smd circle
			(at 0.40005 0 180)
			(size 0 0)
			(layers "F.Cu" "F.Mask" "F.Paste")
			(net "GND")
		)
	)
	(footprint ""
		(layer "F.Cu")
		(at 6.870192 -389.439912)
		(property "Reference" "H3"
			(at -2.5146 -3.58013 0)
			(unlocked yes)
			(layer "F.SilkS")
			(effects
				(font
					(size 0.7874 0.5842)
					(thickness 0.1524)
				)
				(justify left)
			)
		)
		(property "Value" ""
			(at 0 0 0)
			(layer "F.Fab")
			(effects
				(font
					(size 1.27 1.27)
				)
			)
		)
		(duplicate_pad_numbers_are_jumpers no)
		(pad "1" thru_hole circle
			(at 0 0)
			(size 6.1976 6.1976)
			(drill 3.7338)
			(layers "*.Cu" "*.Mask")
			(remove_unused_layers no)
			(net "GND")
			(clearance -0.9779)
			(padstack
				(mode front_inner_back)
				(layer "Inner"
					(shape circle)
					(size 5.5372 5.5372)
					(clearance -0.6477)
				)
				(layer "B.Cu"
					(shape circle)
					(size 6.1976 6.1976)
					(clearance -0.9779)
				)
			)
		)
	)
)
